(kicad_pcb
	(version 20260206)
	(generator "pcbnew")
	(generator_version "10.0")
	(general
		(thickness 1.6)
		(legacy_teardrops no)
	)
	(paper "A4")
	(title_block
		(title "v2-tray-backplane — ms_tbp_v2.brd")
		(comment 1 "Open CloudServer (Microsoft) / footprints 1-8 of 164")
	)
	(layers
		(0 "F.Cu" signal "TOP")
		(4 "In1.Cu" signal "LYR2")
		(6 "In2.Cu" signal "LYR3")
		(8 "In3.Cu" signal "LYR4")
		(10 "In4.Cu" signal "LYR5")
		(12 "In5.Cu" signal "LYR6")
		(14 "In6.Cu" signal "LYR7")
		(2 "B.Cu" signal "BOTTOM")
		(9 "F.Adhes" user "F.Adhesive")
		(11 "B.Adhes" user "B.Adhesive")
		(13 "F.Paste" user "Package Geometry/Pastemask Top")
		(15 "B.Paste" user "Package Geometry/Pastemask Bottom")
		(5 "F.SilkS" user "Ref Des/Silkscreen Top")
		(7 "B.SilkS" user "Ref Des/Silkscreen Bottom")
		(1 "F.Mask" user "Board Geometry/Soldermask Top")
		(3 "B.Mask" user "Board Geometry/Soldermask Bottom")
		(17 "Dwgs.User" user "User.Drawings")
		(19 "Cmts.User" user "User.Comments")
		(21 "Eco1.User" user "User.Eco1")
		(23 "Eco2.User" user "User.Eco2")
		(25 "Edge.Cuts" user "Board Geometry/Outline")
		(27 "Margin" user)
		(31 "F.CrtYd" user "Package Geometry/Place Bound Top")
		(29 "B.CrtYd" user "Package Geometry/Place Bound Bottom")
		(35 "F.Fab" user "Ref Des/Assembly Top")
		(33 "B.Fab" user "Ref Des/Assembly Bottom")
	)
	(footprint ""
		(layer "F.Cu")
		(at -269.044001 12.916002 90)
		(property "Reference" "C29"
			(at -2.430678 -0.180759 90)
			(unlocked yes)
			(layer "F.SilkS")
			(effects
				(font
					(size 0.762 0.5334)
					(thickness 0.1016)
				)
			)
		)
		(property "Value" ""
			(at 0 0 90)
			(layer "F.Fab")
			(effects
				(font
					(size 1.27 1.27)
				)
			)
		)
		(duplicate_pad_numbers_are_jumpers no)
		(fp_poly
			(pts
				(xy -0.999299 0.504) (xy -0.999299 -0.503999) (xy 0.9993 -0.503999) (xy 0.9993 0.504)
			)
			(stroke
				(width 0)
				(type default)
			)
			(fill no)
			(layer "F.CrtYd")
		)
		(fp_line
			(start 0.499999 -0.249999)
			(end 0.499999 0.25)
			(stroke
				(width 0.1)
				(type default)
			)
			(layer "F.Fab")
		)
		(fp_line
			(start -0.499999 -0.249999)
			(end 0.499999 -0.249999)
			(stroke
				(width 0.1)
				(type default)
			)
			(layer "F.Fab")
		)
		(fp_line
			(start 0.499999 0.25)
			(end -0.499999 0.25)
			(stroke
				(width 0.1)
				(type default)
			)
			(layer "F.Fab")
		)
		(fp_line
			(start -0.499999 0.25)
			(end -0.499999 -0.249999)
			(stroke
				(width 0.1)
				(type default)
			)
			(layer "F.Fab")
		)
		(pad "1" smd rect
			(at -0.4572 0 180)
			(size 0.508 0.5842)
			(layers "F.Cu" "F.Mask" "F.Paste")
			(net "P3V3_40G_B1_VCC1")
		)
		(pad "2" smd rect
			(at 0.4572 0 180)
			(size 0.508 0.5842)
			(layers "F.Cu" "F.Mask" "F.Paste")
			(net "GND")
		)
	)
	(footprint ""
		(layer "F.Cu")
		(at -110.8456 18.8214)
		(property "Reference" "R34"
			(at 2.5146 0.0127 0)
			(unlocked yes)
			(layer "F.SilkS")
			(effects
				(font
					(size 0.762 0.5334)
					(thickness 0.1016)
				)
			)
		)
		(property "Value" ""
			(at 0 0 0)
			(layer "F.Fab")
			(effects
				(font
					(size 1.27 1.27)
				)
			)
		)
		(duplicate_pad_numbers_are_jumpers no)
		(fp_line
			(start 0 -0.381)
			(end 0 0.381)
			(stroke
				(width 0.127)
				(type default)
			)
			(layer "F.SilkS")
		)
		(fp_poly
			(pts
				(xy 1.255601 0.6564) (xy -1.255601 0.6564) (xy -1.255601 -0.656399) (xy 1.255601 -0.656399)
			)
			(stroke
				(width 0)
				(type default)
			)
			(fill no)
			(layer "F.CrtYd")
		)
		(fp_line
			(start -0.800001 -0.399999)
			(end -0.800001 0.399999)
			(stroke
				(width 0.1)
				(type default)
			)
			(layer "F.Fab")
		)
		(fp_line
			(start -0.800001 0.399999)
			(end 0.800001 0.399999)
			(stroke
				(width 0.1)
				(type default)
			)
			(layer "F.Fab")
		)
		(fp_line
			(start 0.800001 -0.399999)
			(end -0.800001 -0.399999)
			(stroke
				(width 0.1)
				(type default)
			)
			(layer "F.Fab")
		)
		(fp_line
			(start 0.800001 0.399999)
			(end 0.800001 -0.399999)
			(stroke
				(width 0.1)
				(type default)
			)
			(layer "F.Fab")
		)
		(pad "1" smd rect
			(at -0.650001 0)
			(size 0.7112 0.8128)
			(layers "F.Cu" "F.Mask" "F.Paste")
			(net "P3V3_B2_QSFP")
		)
		(pad "2" smd rect
			(at 0.650001 0 180)
			(size 0.7112 0.8128)
			(layers "F.Cu" "F.Mask" "F.Paste")
			(net "SKU_B2_ID2")
		)
	)
	(footprint ""
		(layer "F.Cu")
		(at -75.3618 9.652)
		(property "Reference" "R50"
			(at 2.9718 0.1143 0)
			(unlocked yes)
			(layer "F.SilkS")
			(effects
				(font
					(size 0.762 0.5334)
					(thickness 0.1016)
				)
			)
		)
		(property "Value" ""
			(at 0 0 0)
			(layer "F.Fab")
			(effects
				(font
					(size 1.27 1.27)
				)
			)
		)
		(duplicate_pad_numbers_are_jumpers no)
		(fp_line
			(start 0 -0.381)
			(end 0 0.381)
			(stroke
				(width 0.127)
				(type default)
			)
			(layer "F.SilkS")
		)
		(fp_poly
			(pts
				(xy 1.255601 0.6564) (xy -1.255601 0.6564) (xy -1.255601 -0.656399) (xy 1.255601 -0.656399)
			)
			(stroke
				(width 0)
				(type default)
			)
			(fill no)
			(layer "F.CrtYd")
		)
		(fp_line
			(start -0.800001 -0.399999)
			(end -0.800001 0.399999)
			(stroke
				(width 0.1)
				(type default)
			)
			(layer "F.Fab")
		)
		(fp_line
			(start -0.800001 0.399999)
			(end 0.800001 0.399999)
			(stroke
				(width 0.1)
				(type default)
			)
			(layer "F.Fab")
		)
		(fp_line
			(start 0.800001 -0.399999)
			(end -0.800001 -0.399999)
			(stroke
				(width 0.1)
				(type default)
			)
			(layer "F.Fab")
		)
		(fp_line
			(start 0.800001 0.399999)
			(end 0.800001 -0.399999)
			(stroke
				(width 0.1)
				(type default)
			)
			(layer "F.Fab")
		)
		(pad "1" smd rect
			(at -0.650001 0)
			(size 0.7112 0.8128)
			(layers "F.Cu" "F.Mask" "F.Paste")
			(net "P3V3_B2_QSFP")
		)
		(pad "2" smd rect
			(at 0.650001 0 180)
			(size 0.7112 0.8128)
			(layers "F.Cu" "F.Mask" "F.Paste")
			(net "ETH10G_B2_RS0")
		)
	)
	(footprint ""
		(layer "F.Cu")
		(at -75.329199 3.873398)
		(property "Reference" "R53"
			(at 2.812199 0.101702 0)
			(unlocked yes)
			(layer "F.SilkS")
			(effects
				(font
					(size 0.762 0.5334)
					(thickness 0.1016)
				)
			)
		)
		(property "Value" ""
			(at 0 0 0)
			(layer "F.Fab")
			(effects
				(font
					(size 1.27 1.27)
				)
			)
		)
		(duplicate_pad_numbers_are_jumpers no)
		(fp_line
			(start 0 -0.381)
			(end 0 0.381)
			(stroke
				(width 0.127)
				(type default)
			)
			(layer "F.SilkS")
		)
		(fp_poly
			(pts
				(xy 1.255601 0.6564) (xy -1.255601 0.6564) (xy -1.255601 -0.656399) (xy 1.255601 -0.656399)
			)
			(stroke
				(width 0)
				(type default)
			)
			(fill no)
			(layer "F.CrtYd")
		)
		(fp_line
			(start -0.800001 -0.399999)
			(end -0.800001 0.4)
			(stroke
				(width 0.1)
				(type default)
			)
			(layer "F.Fab")
		)
		(fp_line
			(start -0.800001 0.4)
			(end 0.800001 0.4)
			(stroke
				(width 0.1)
				(type default)
			)
			(layer "F.Fab")
		)
		(fp_line
			(start 0.800001 -0.399999)
			(end -0.800001 -0.399999)
			(stroke
				(width 0.1)
				(type default)
			)
			(layer "F.Fab")
		)
		(fp_line
			(start 0.800001 0.4)
			(end 0.800001 -0.399999)
			(stroke
				(width 0.1)
				(type default)
			)
			(layer "F.Fab")
		)
		(pad "1" smd rect
			(at -0.650001 0)
			(size 0.7112 0.8128)
			(layers "F.Cu" "F.Mask" "F.Paste")
			(net "ETH10G_B2_RS1")
		)
		(pad "2" smd rect
			(at 0.650001 0 180)
			(size 0.7112 0.8128)
			(layers "F.Cu" "F.Mask" "F.Paste")
			(net "GND")
		)
	)
	(footprint ""
		(layer "F.Cu")
		(at -115.221601 21.272602 90)
		(property "Reference" "C15"
			(at -2.857398 -0.056299 90)
			(unlocked yes)
			(layer "F.SilkS")
			(effects
				(font
					(size 0.762 0.5334)
					(thickness 0.1016)
				)
			)
		)
		(property "Value" ""
			(at 0 0 90)
			(layer "F.Fab")
			(effects
				(font
					(size 1.27 1.27)
				)
			)
		)
		(duplicate_pad_numbers_are_jumpers no)
		(fp_poly
			(pts
				(xy -0.999299 0.504) (xy -0.999299 -0.503999) (xy 0.9993 -0.503999) (xy 0.9993 0.504)
			)
			(stroke
				(width 0)
				(type default)
			)
			(fill no)
			(layer "F.CrtYd")
		)
		(fp_line
			(start 0.499999 -0.249999)
			(end 0.499999 0.25)
			(stroke
				(width 0.1)
				(type default)
			)
			(layer "F.Fab")
		)
		(fp_line
			(start -0.499999 -0.249999)
			(end 0.499999 -0.249999)
			(stroke
				(width 0.1)
				(type default)
			)
			(layer "F.Fab")
		)
		(fp_line
			(start 0.499999 0.25)
			(end -0.499999 0.25)
			(stroke
				(width 0.1)
				(type default)
			)
			(layer "F.Fab")
		)
		(fp_line
			(start -0.499999 0.25)
			(end -0.499999 -0.249999)
			(stroke
				(width 0.1)
				(type default)
			)
			(layer "F.Fab")
		)
		(pad "1" smd rect
			(at -0.4572 0 180)
			(size 0.508 0.5842)
			(layers "F.Cu" "F.Mask" "F.Paste")
			(net "P12V")
		)
		(pad "2" smd rect
			(at 0.4572 0 180)
			(size 0.508 0.5842)
			(layers "F.Cu" "F.Mask" "F.Paste")
			(net "GND")
		)
	)
	(footprint ""
		(layer "F.Cu")
		(at -240.919 43.942 -90)
		(property "Reference" "R1"
			(at 0.412775 -1.400449 90)
			(unlocked yes)
			(layer "F.SilkS")
			(effects
				(font
					(size 0.762 0.5334)
					(thickness 0.1016)
				)
			)
		)
		(property "Value" ""
			(at 0 0 270)
			(layer "F.Fab")
			(effects
				(font
					(size 1.27 1.27)
				)
			)
		)
		(duplicate_pad_numbers_are_jumpers no)
		(fp_line
			(start 0 -0.381)
			(end 0 0.381)
			(stroke
				(width 0.127)
				(type default)
			)
			(layer "F.SilkS")
		)
		(fp_poly
			(pts
				(xy 1.255601 0.6564) (xy -1.255601 0.6564) (xy -1.255601 -0.656399) (xy 1.255601 -0.656399)
			)
			(stroke
				(width 0)
				(type default)
			)
			(fill no)
			(layer "F.CrtYd")
		)
		(fp_line
			(start -0.800001 0.399999)
			(end 0.800001 0.399999)
			(stroke
				(width 0.1)
				(type default)
			)
			(layer "F.Fab")
		)
		(fp_line
			(start 0.800001 0.399999)
			(end 0.800001 -0.399999)
			(stroke
				(width 0.1)
				(type default)
			)
			(layer "F.Fab")
		)
		(fp_line
			(start -0.800001 -0.399999)
			(end -0.800001 0.399999)
			(stroke
				(width 0.1)
				(type default)
			)
			(layer "F.Fab")
		)
		(fp_line
			(start 0.800001 -0.399999)
			(end -0.800001 -0.399999)
			(stroke
				(width 0.1)
				(type default)
			)
			(layer "F.Fab")
		)
		(pad "1" smd rect
			(at -0.650001 0 270)
			(size 0.7112 0.8128)
			(layers "F.Cu" "F.Mask" "F.Paste")
			(net "GND")
		)
		(pad "2" smd rect
			(at 0.650001 0 90)
			(size 0.7112 0.8128)
			(layers "F.Cu" "F.Mask" "F.Paste")
			(net "JBOD_B1_MATED_N")
		)
	)
	(footprint ""
		(layer "F.Cu")
		(at -123.551 4.7244 -90)
		(property "Reference" "R39"
			(at 0.08128 1.22904 90)
			(unlocked yes)
			(layer "F.SilkS")
			(effects
				(font
					(size 0.762 0.5334)
					(thickness 0.1016)
				)
			)
		)
		(property "Value" ""
			(at 0 0 270)
			(layer "F.Fab")
			(effects
				(font
					(size 1.27 1.27)
				)
			)
		)
		(duplicate_pad_numbers_are_jumpers no)
		(fp_line
			(start 0 -0.381)
			(end 0 0.381)
			(stroke
				(width 0.127)
				(type default)
			)
			(layer "F.SilkS")
		)
		(fp_poly
			(pts
				(xy 1.255601 0.6564) (xy -1.255601 0.6564) (xy -1.255601 -0.656399) (xy 1.255601 -0.656399)
			)
			(stroke
				(width 0)
				(type default)
			)
			(fill no)
			(layer "F.CrtYd")
		)
		(fp_line
			(start -0.800001 0.399999)
			(end 0.800001 0.399999)
			(stroke
				(width 0.1)
				(type default)
			)
			(layer "F.Fab")
		)
		(fp_line
			(start 0.800001 0.399999)
			(end 0.800001 -0.399999)
			(stroke
				(width 0.1)
				(type default)
			)
			(layer "F.Fab")
		)
		(fp_line
			(start -0.800001 -0.399999)
			(end -0.800001 0.399999)
			(stroke
				(width 0.1)
				(type default)
			)
			(layer "F.Fab")
		)
		(fp_line
			(start 0.800001 -0.399999)
			(end -0.800001 -0.399999)
			(stroke
				(width 0.1)
				(type default)
			)
			(layer "F.Fab")
		)
		(pad "1" smd rect
			(at -0.650001 0 270)
			(size 0.7112 0.8128)
			(layers "F.Cu" "F.Mask" "F.Paste")
			(net "UNNAMED_6_1X2HDR_I56_IO")
		)
		(pad "2" smd rect
			(at 0.650001 0 90)
			(size 0.7112 0.8128)
			(layers "F.Cu" "F.Mask" "F.Paste")
			(net "GND")
		)
	)
	(footprint ""
		(layer "F.Cu")
		(at -337.250049 32.460001)
		(property "Reference" "J4"
			(at 4.129049 -6.767901 0)
			(unlocked yes)
			(layer "F.SilkS")
			(effects
				(font
					(size 0.762 0.5334)
					(thickness 0.1016)
				)
			)
		)
		(property "Value" ""
			(at 0 0 0)
			(layer "F.Fab")
			(effects
				(font
					(size 1.27 1.27)
				)
			)
		)
		(duplicate_pad_numbers_are_jumpers no)
		(fp_line
			(start -1.925 -5.549999)
			(end 9.924999 -5.549999)
			(stroke
				(width 0.127)
				(type default)
			)
			(layer "F.SilkS")
		)
		(fp_line
			(start -1.925 23.750001)
			(end -1.925 -5.549999)
			(stroke
				(width 0.127)
				(type default)
			)
			(layer "F.SilkS")
		)
		(fp_line
			(start 9.924999 -5.549999)
			(end 9.924999 23.750001)
			(stroke
				(width 0.127)
				(type default)
			)
			(layer "F.SilkS")
		)
		(fp_line
			(start 9.924999 23.750001)
			(end -1.925 23.750001)
			(stroke
				(width 0.127)
				(type default)
			)
			(layer "F.SilkS")
		)
		(fp_poly
			(pts
				(arc
					(start 7.999999 -5.2)
					(mid 11.676954 -3.676955)
					(end 13.199999 0)
				)
				(arc
					(start 13.199999 11.999999)
					(mid 11.676955 15.676956)
					(end 7.999999 17.200001)
				)
				(arc
					(start 0 17.200001)
					(mid -3.676956 15.676955)
					(end -5.2 11.999999)
				)
				(arc
					(start -5.2 0)
					(mid -3.676955 -3.676955)
					(end 0 -5.2)
				)
			)
			(stroke
				(width 0)
				(type default)
			)
			(fill no)
			(layer "B.CrtYd")
		)
		(fp_poly
			(pts
				(xy 10.924999 24.749999) (xy -2.925001 24.749999) (xy -2.925001 -6.549999) (xy 10.924999 -6.549999)
			)
			(stroke
				(width 0)
				(type default)
			)
			(fill no)
			(layer "F.CrtYd")
		)
		(fp_line
			(start -1.925 -5.549999)
			(end 9.924999 -5.549999)
			(stroke
				(width 0.1)
				(type default)
			)
			(layer "F.Fab")
		)
		(fp_line
			(start -1.925 23.750001)
			(end -1.925 -5.549999)
			(stroke
				(width 0.1)
				(type default)
			)
			(layer "F.Fab")
		)
		(fp_line
			(start 9.924999 -5.549999)
			(end 9.924999 23.750001)
			(stroke
				(width 0.1)
				(type default)
			)
			(layer "F.Fab")
		)
		(fp_line
			(start 9.924999 23.750001)
			(end -1.925 23.750001)
			(stroke
				(width 0.1)
				(type default)
			)
			(layer "F.Fab")
		)
		(fp_text user "*"
			(at -0.360401 -6.425001 90)
			(unlocked yes)
			(layer "F.SilkS")
			(effects
				(font
					(size 0.381 0.381)
					(thickness 0.381)
				)
			)
		)
		(fp_text user "2"
			(at 10.499999 -0.3469 0)
			(unlocked yes)
			(layer "F.SilkS")
			(effects
				(font
					(size 0.762 0.5334)
					(thickness 0.1016)
				)
			)
		)
		(fp_text user "3"
			(at 10.499999 7.907099 0)
			(unlocked yes)
			(layer "F.SilkS")
			(effects
				(font
					(size 0.762 0.5334)
					(thickness 0.1016)
				)
			)
		)
		(pad "" np_thru_hole circle
			(at 4 5.499999)
			(size 1.27 1.27)
			(drill 2.1844)
			(layers "*.Cu" "*.Mask")
		)
		(pad "1A" thru_hole rect
			(at 0 0)
			(size 1.3716 1.3716)
			(drill 0.762)
			(layers "*.Cu" "*.Mask")
			(remove_unused_layers no)
			(net "GND")
			(padstack
				(mode front_inner_back)
				(layer "Inner"
					(shape circle)
					(size 1.3716 1.3716)
				)
				(layer "B.Cu"
					(shape rect)
					(size 1.3716 1.3716)
				)
			)
		)
		(pad "1B" thru_hole circle
			(at 2.000001 0)
			(size 1.3716 1.3716)
			(drill 0.762)
			(layers "*.Cu" "*.Mask")
			(remove_unused_layers no)
			(net "GND")
		)
		(pad "1C" thru_hole circle
			(at 0 2.000001)
			(size 1.3716 1.3716)
			(drill 0.762)
			(layers "*.Cu" "*.Mask")
			(remove_unused_layers no)
			(net "GND")
		)
		(pad "1D" thru_hole circle
			(at 2.000001 2.000001)
			(size 1.3716 1.3716)
			(drill 0.762)
			(layers "*.Cu" "*.Mask")
			(remove_unused_layers no)
			(net "GND")
		)
		(pad "1E" thru_hole circle
			(at 0 4)
			(size 1.3716 1.3716)
			(drill 0.762)
			(layers "*.Cu" "*.Mask")
			(remove_unused_layers no)
			(net "GND")
		)
		(pad "1F" thru_hole circle
			(at 2.000001 4)
			(size 1.3716 1.3716)
			(drill 0.762)
			(layers "*.Cu" "*.Mask")
			(remove_unused_layers no)
			(net "GND")
		)
		(pad "2A" thru_hole circle
			(at 6.000001 0)
			(size 1.3716 1.3716)
			(drill 0.762)
			(layers "*.Cu" "*.Mask")
			(remove_unused_layers no)
			(net "P12V")
		)
		(pad "2B" thru_hole circle
			(at 7.999999 0)
			(size 1.3716 1.3716)
			(drill 0.762)
			(layers "*.Cu" "*.Mask")
			(remove_unused_layers no)
			(net "P12V")
		)
		(pad "2C" thru_hole circle
			(at 6.000001 2.000001)
			(size 1.3716 1.3716)
			(drill 0.762)
			(layers "*.Cu" "*.Mask")
			(remove_unused_layers no)
			(net "P12V")
		)
		(pad "2D" thru_hole circle
			(at 7.999999 2.000001)
			(size 1.3716 1.3716)
			(drill 0.762)
			(layers "*.Cu" "*.Mask")
			(remove_unused_layers no)
			(net "P12V")
		)
		(pad "2E" thru_hole circle
			(at 6.000001 4)
			(size 1.3716 1.3716)
			(drill 0.762)
			(layers "*.Cu" "*.Mask")
			(remove_unused_layers no)
			(net "P12V")
		)
		(pad "2F" thru_hole circle
			(at 7.999999 4)
			(size 1.3716 1.3716)
			(drill 0.762)
			(layers "*.Cu" "*.Mask")
			(remove_unused_layers no)
			(net "P12V")
		)
		(pad "3A" thru_hole circle
			(at 6.000001 7.999999)
			(size 1.3716 1.3716)
			(drill 0.762)
			(layers "*.Cu" "*.Mask")
			(remove_unused_layers no)
			(net "P12V")
		)
		(pad "3B" thru_hole circle
			(at 7.999999 7.999999)
			(size 1.3716 1.3716)
			(drill 0.762)
			(layers "*.Cu" "*.Mask")
			(remove_unused_layers no)
			(net "P12V")
		)
		(pad "3C" thru_hole circle
			(at 6.000001 10)
			(size 1.3716 1.3716)
			(drill 0.762)
			(layers "*.Cu" "*.Mask")
			(remove_unused_layers no)
			(net "P12V")
		)
		(pad "3D" thru_hole circle
			(at 7.999999 10)
			(size 1.3716 1.3716)
			(drill 0.762)
			(layers "*.Cu" "*.Mask")
			(remove_unused_layers no)
			(net "P12V")
		)
		(pad "3E" thru_hole circle
			(at 6.000001 11.999999)
			(size 1.3716 1.3716)
			(drill 0.762)
			(layers "*.Cu" "*.Mask")
			(remove_unused_layers no)
			(net "P12V")
		)
		(pad "3F" thru_hole circle
			(at 7.999999 11.999999)
			(size 1.3716 1.3716)
			(drill 0.762)
			(layers "*.Cu" "*.Mask")
			(remove_unused_layers no)
			(net "P12V")
		)
		(pad "4A" thru_hole circle
			(at 0 7.999999)
			(size 1.3716 1.3716)
			(drill 0.762)
			(layers "*.Cu" "*.Mask")
			(remove_unused_layers no)
			(net "GND")
		)
		(pad "4B" thru_hole circle
			(at 2.000001 7.999999)
			(size 1.3716 1.3716)
			(drill 0.762)
			(layers "*.Cu" "*.Mask")
			(remove_unused_layers no)
			(net "GND")
		)
		(pad "4C" thru_hole circle
			(at 0 10)
			(size 1.3716 1.3716)
			(drill 0.762)
			(layers "*.Cu" "*.Mask")
			(remove_unused_layers no)
			(net "GND")
		)
		(pad "4D" thru_hole circle
			(at 2.000001 10)
			(size 1.3716 1.3716)
			(drill 0.762)
			(layers "*.Cu" "*.Mask")
			(remove_unused_layers no)
			(net "GND")
		)
		(pad "4E" thru_hole circle
			(at 0 11.999999)
			(size 1.3716 1.3716)
			(drill 0.762)
			(layers "*.Cu" "*.Mask")
			(remove_unused_layers no)
			(net "GND")
		)
		(pad "4F" thru_hole circle
			(at 2.000001 11.999999)
			(size 1.3716 1.3716)
			(drill 0.762)
			(layers "*.Cu" "*.Mask")
			(remove_unused_layers no)
			(net "GND")
		)
		(zone
			(layers "F.Cu" "B.Cu" "In1.Cu" "In2.Cu" "In3.Cu" "In4.Cu" "In5.Cu" "In6.Cu")
			(hatch none 0.5)
			(connect_pads
				(clearance 0)
			)
			(min_thickness 0.25)
			(keepout
				(tracks not_allowed)
				(vias allowed)
				(pads allowed)
				(copperpour not_allowed)
				(footprints allowed)
			)
			(placement
				(enabled no)
				(sheetname "")
			)
			(fill
				(thermal_gap 0.5)
				(thermal_bridge_width 0.5)
				(island_removal_mode 0)
			)
			(polygon
				(pts
					(arc
						(start -331.77685 37.96)
						(mid -334.72325 37.96)
						(end -331.77685 37.96)
					)
				)
			)
		)
	)
)
